FILE_TYPE = CONNECTIVITY;
{Allegro Design Entry HDL 17.2-2016 S081 (4005846) 1/11/2022}
"PAGE_NUMBER" = 18;
0"NC";
1"TP_CPU0_SPARE4";
2"TP_CPU0_PPD";
3"TP_CPU0_SPARE6";
4"TP_CPU0_SPARE10";
5"TP_CPU0_SPARE8";
6"TP_CPU0_SPARE11";
7"TP_CPU0_SPARE5";
8"TP_CPU0_SPARE9";
9"TP_CPU0_SPARE13";
10"TP_CPU0_SPARE7";
11"TP_CPU0_SPARE12";
%"SOCKET4677_AZIF0045P001C01CS"
"6","(1750,2600)","0","pure_quanta","I1";
;
PART_NUMBER"DGA^7000023"
PART_TYPE"SMLF"
MATERIAL"IO"
VALUE"SOCKET4677_AZIF0045-P001C01CS"
$LOCATION"U2"
CDS_LIB"pure_quanta"
NEEDS_NO_SIZE"TRUE"
CDS_LMAN_SYM_OUTLINE"-1050,400,1050,-400"
CDS_LOCATION"U2"
$SEC"6"
CDS_SEC"6";
"RSVD163"
$PN"J13"2;
"RSVD95"
$PN"CG60"4;
"RSVD111"
$PN"CK61"5;
"RSVD87"
$PN"CD69"6;
"RSVD8"
$PN"AU52"7;
"RSVD97"
$PN"CH61"8;
"RSVD44"
$PN"BD77"9;
"RSVD159"
$PN"DA70"1;
"RSVD148"
$PN"CW43"3;
"RSVD115"
$PN"CL60"10;
"RSVD119"
$PN"CL70"11;
END.
